# T6G (Grand Teton) — schematic netlist excerpt (pin names and nets, part order shuffled) for the footprints in the layout excerpt that follows; sources: Cadence DE-HDL packaged netlist, KiCad conversion of 04192023_DAF0TMB3IC0_F0TG_MB_C_brd_V02_OCP.brd

C930  Q_CAP_DIFFBUS  DIFF BUS_0.22UF 6.3V 20% X6S  pkg C0201  page 63 : \1\ = P5E_CPU0_P0_TX_C_DN<1> ; \2\ = P5E_CPU0_P0_TX_DN<1>

Q1  MOSFET_NCH_DUAL  PJT138K IC  pkg SOT363XD  page 188
  S1  = GND
  G1  = PWRGD_P5V_R1
  D2  = PWRGD_P5V_R2
  S2  = GND
  G2  = PWRGD_P5V_N
  D1  = PWRGD_P5V_R_N

PC630  Q_CAP  0.22UF 16V 10% X7R  pkg 0402  page 223 : A = SW_PVDDIO_P1_BOOT4_R ; B = SW_PVDDIO_P1_BOOTR4

(kicad_pcb
	(version 20260206)
	(generator "pcbnew")
	(generator_version "10.0")
	(general
		(thickness 1.6)
		(legacy_teardrops no)
	)
	(paper "A4")
	(title_block
		(title "04192023_DAF0TMB3IC0_F0TG_MB_C_brd_V02_OCP.brd")
		(comment 1 "Grand Teton / footprints 1354-1356 of 8354")
	)
	(layers
		(0 "F.Cu" signal "TOP")
		(4 "In1.Cu" signal "GND")
		(6 "In2.Cu" signal "IN1")
		(8 "In3.Cu" signal "GND1")
		(10 "In4.Cu" signal "IN2")
		(12 "In5.Cu" signal "GND2")
		(14 "In6.Cu" signal "IN3")
		(16 "In7.Cu" signal "GND3")
		(18 "In8.Cu" signal "VCC")
		(20 "In9.Cu" signal "VCC1")
		(22 "In10.Cu" signal "GND4")
		(24 "In11.Cu" signal "IN4")
		(26 "In12.Cu" signal "GND5")
		(28 "In13.Cu" signal "IN5")
		(30 "In14.Cu" signal "GND6")
		(32 "In15.Cu" signal "IN6")
		(34 "In16.Cu" signal "GND7")
		(2 "B.Cu" signal "BOTTOM")
		(9 "F.Adhes" user "F.Adhesive")
		(11 "B.Adhes" user "B.Adhesive")
		(13 "F.Paste" user "Package Geometry/Pastemask Top")
		(15 "B.Paste" user "Package Geometry/Pastemask Bottom")
		(5 "F.SilkS" user "Ref Des/Silkscreen Top")
		(7 "B.SilkS" user "Ref Des/Silkscreen Bottom")
		(1 "F.Mask" user "Board Geometry/Soldermask Top")
		(3 "B.Mask" user "Board Geometry/Soldermask Bottom")
		(17 "Dwgs.User" user "User.Drawings")
		(19 "Cmts.User" user "User.Comments")
		(21 "Eco1.User" user "User.Eco1")
		(23 "Eco2.User" user "User.Eco2")
		(25 "Edge.Cuts" user "Board Geometry/Outline")
		(27 "Margin" user)
		(31 "F.CrtYd" user "Package Geometry/Place Bound Top")
		(29 "B.CrtYd" user "Package Geometry/Place Bound Bottom")
		(35 "F.Fab" user "Ref Des/Assembly Top")
		(33 "B.Fab" user "Ref Des/Assembly Bottom")
	)
	(footprint ""
		(layer "F.Cu")
		(at 163.383976 -129.549652)
		(property "Reference" "Q1"
			(at -2.297176 -2.115566 0)
			(unlocked yes)
			(layer "F.SilkS")
			(effects
				(font
					(size 0.7874 0.5842)
					(thickness 0.1524)
				)
				(justify left)
			)
		)
		(property "Value" ""
			(at 0 0 0)
			(layer "F.Fab")
			(effects
				(font
					(size 1.27 1.27)
				)
			)
		)
		(duplicate_pad_numbers_are_jumpers no)
		(fp_line
			(start -1.332738 -1.100074)
			(end -0.4826 -1.100074)
			(stroke
				(width 0.1524)
				(type default)
			)
			(layer "F.SilkS")
		)
		(fp_line
			(start -1.332738 1.100074)
			(end -1.332738 -1.100074)
			(stroke
				(width 0.1524)
				(type default)
			)
			(layer "F.SilkS")
		)
		(fp_line
			(start -0.4826 -1.100074)
			(end 0 -0.541274)
			(stroke
				(width 0.1524)
				(type default)
			)
			(layer "F.SilkS")
		)
		(fp_line
			(start 0 -0.541274)
			(end 0.4826 -1.100074)
			(stroke
				(width 0.1524)
				(type default)
			)
			(layer "F.SilkS")
		)
		(fp_line
			(start 0.4826 -1.100074)
			(end 1.332738 -1.100074)
			(stroke
				(width 0.1524)
				(type default)
			)
			(layer "F.SilkS")
		)
		(fp_line
			(start 1.332738 -1.100074)
			(end 1.332738 1.100074)
			(stroke
				(width 0.1524)
				(type default)
			)
			(layer "F.SilkS")
		)
		(fp_line
			(start 1.332738 1.100074)
			(end -1.332738 1.100074)
			(stroke
				(width 0.1524)
				(type default)
			)
			(layer "F.SilkS")
		)
		(fp_poly
			(pts
				(xy -2.72542 -0.998982) (xy -2.446782 -1.64338) (xy -1.94183 -1.042416)
			)
			(stroke
				(width 0)
				(type default)
			)
			(fill yes)
			(layer "F.SilkS")
		)
		(fp_line
			(start -0.674878 -1.100074)
			(end 0.674878 -1.100074)
			(stroke
				(width 0.1)
				(type default)
			)
			(layer "F.Fab")
		)
		(fp_line
			(start -0.674878 1.100074)
			(end -0.674878 -1.100074)
			(stroke
				(width 0.1)
				(type default)
			)
			(layer "F.Fab")
		)
		(fp_line
			(start 0.674878 -1.100074)
			(end 0.674878 1.100074)
			(stroke
				(width 0.1)
				(type default)
			)
			(layer "F.Fab")
		)
		(fp_line
			(start 0.674878 1.100074)
			(end -0.674878 1.100074)
			(stroke
				(width 0.1)
				(type default)
			)
			(layer "F.Fab")
		)
		(fp_poly
			(pts
				(xy -2.2352 -0.298958) (xy -2.2352 -1.001014) (xy -1.533144 -0.649986)
			)
			(stroke
				(width 0)
				(type default)
			)
			(fill yes)
			(layer "F.Fab")
		)
		(pad "1" smd rect
			(at -0.94996 -0.649986 90)
			(size 0.4318 0.508)
			(layers "F.Cu" "F.Mask" "F.Paste")
			(net "GND")
		)
		(pad "2" smd rect
			(at -0.94996 0 90)
			(size 0.4318 0.508)
			(layers "F.Cu" "F.Mask" "F.Paste")
			(net "PWRGD_P5V_R1")
		)
		(pad "3" smd rect
			(at -0.94996 0.649986 90)
			(size 0.4318 0.508)
			(layers "F.Cu" "F.Mask" "F.Paste")
			(net "PWRGD_P5V_R2")
		)
		(pad "4" smd rect
			(at 0.94996 0.649986 90)
			(size 0.4318 0.508)
			(layers "F.Cu" "F.Mask" "F.Paste")
			(net "GND")
		)
		(pad "5" smd rect
			(at 0.94996 0 90)
			(size 0.4318 0.508)
			(layers "F.Cu" "F.Mask" "F.Paste")
			(net "PWRGD_P5V_N")
		)
		(pad "6" smd rect
			(at 0.94996 -0.649986 90)
			(size 0.4318 0.508)
			(layers "F.Cu" "F.Mask" "F.Paste")
			(net "PWRGD_P5V_R_N")
		)
	)
	(footprint ""
		(layer "F.Cu")
		(at 298.967144 -385.23926 180)
		(property "Reference" "C930"
			(at 0 0 180)
			(layer "F.SilkS")
			(hide yes)
			(effects
				(font
					(size 1.27 1.27)
				)
			)
		)
		(property "Value" ""
			(at 0 0 180)
			(layer "F.Fab")
			(effects
				(font
					(size 1.27 1.27)
				)
			)
		)
		(duplicate_pad_numbers_are_jumpers no)
		(fp_line
			(start 0.299974 0.150114)
			(end -0.299974 0.150114)
			(stroke
				(width 0.1)
				(type default)
			)
			(layer "F.Fab")
		)
		(fp_line
			(start 0.299974 -0.150114)
			(end 0.299974 0.150114)
			(stroke
				(width 0.1)
				(type default)
			)
			(layer "F.Fab")
		)
		(fp_line
			(start -0.299974 0.150114)
			(end -0.299974 -0.150114)
			(stroke
				(width 0.1)
				(type default)
			)
			(layer "F.Fab")
		)
		(fp_line
			(start -0.299974 -0.150114)
			(end 0.299974 -0.150114)
			(stroke
				(width 0.1)
				(type default)
			)
			(layer "F.Fab")
		)
		(pad "1" smd rect
			(at -0.2667 0 180)
			(size 0.3048 0.381)
			(layers "F.Cu" "F.Mask" "F.Paste")
			(net "P5E_CPU0_P0_TX_C_DN<1>")
		)
		(pad "2" smd rect
			(at 0.2667 0 180)
			(size 0.3048 0.381)
			(layers "F.Cu" "F.Mask" "F.Paste")
			(net "P5E_CPU0_P0_TX_DN<1>")
		)
	)
	(footprint ""
		(layer "F.Cu")
		(at 30.386528 -351.372932 -90)
		(property "Reference" "PC630"
			(at 0 0 270)
			(layer "F.SilkS")
			(hide yes)
			(effects
				(font
					(size 1.27 1.27)
				)
			)
		)
		(property "Value" ""
			(at 0 0 270)
			(layer "F.Fab")
			(effects
				(font
					(size 1.27 1.27)
				)
			)
		)
		(duplicate_pad_numbers_are_jumpers no)
		(fp_line
			(start -0.7874 0.4064)
			(end -0.7874 -0.4064)
			(stroke
				(width 0.1524)
				(type default)
			)
			(layer "F.SilkS")
		)
		(fp_line
			(start 0.7874 0.4064)
			(end -0.7874 0.4064)
			(stroke
				(width 0.1524)
				(type default)
			)
			(layer "F.SilkS")
		)
		(fp_line
			(start -0.7874 -0.4064)
			(end 0.7874 -0.4064)
			(stroke
				(width 0.1524)
				(type default)
			)
			(layer "F.SilkS")
		)
		(fp_line
			(start 0.7874 -0.4064)
			(end 0.7874 0.4064)
			(stroke
				(width 0.1524)
				(type default)
			)
			(layer "F.SilkS")
		)
		(fp_line
			(start -0.67945 0.3048)
			(end -0.67945 -0.305054)
			(stroke
				(width 0.1)
				(type default)
			)
			(layer "F.Fab")
		)
		(fp_line
			(start -0.12065 0.3048)
			(end -0.67945 0.3048)
			(stroke
				(width 0.1)
				(type default)
			)
			(layer "F.Fab")
		)
		(fp_line
			(start 0.120396 0.3048)
			(end 0.120396 0.2794)
			(stroke
				(width 0.1)
				(type default)
			)
			(layer "F.Fab")
		)
		(fp_line
			(start 0.67945 0.3048)
			(end 0.120396 0.3048)
			(stroke
				(width 0.1)
				(type default)
			)
			(layer "F.Fab")
		)
		(fp_line
			(start -0.12065 0.2794)
			(end -0.12065 0.3048)
			(stroke
				(width 0.1)
				(type default)
			)
			(layer "F.Fab")
		)
		(fp_line
			(start 0.120396 0.2794)
			(end -0.12065 0.2794)
			(stroke
				(width 0.1)
				(type default)
			)
			(layer "F.Fab")
		)
		(fp_line
			(start -0.12065 -0.2794)
			(end 0.12065 -0.2794)
			(stroke
				(width 0.1)
				(type default)
			)
			(layer "F.Fab")
		)
		(fp_line
			(start 0.12065 -0.2794)
			(end 0.12065 -0.3048)
			(stroke
				(width 0.1)
				(type default)
			)
			(layer "F.Fab")
		)
		(fp_line
			(start 0.12065 -0.3048)
			(end 0.67945 -0.3048)
			(stroke
				(width 0.1)
				(type default)
			)
			(layer "F.Fab")
		)
		(fp_line
			(start 0.67945 -0.3048)
			(end 0.67945 0.3048)
			(stroke
				(width 0.1)
				(type default)
			)
			(layer "F.Fab")
		)
		(fp_line
			(start -0.67945 -0.305054)
			(end -0.12065 -0.305054)
			(stroke
				(width 0.1)
				(type default)
			)
			(layer "F.Fab")
		)
		(fp_line
			(start -0.12065 -0.305054)
			(end -0.12065 -0.2794)
			(stroke
				(width 0.1)
				(type default)
			)
			(layer "F.Fab")
		)
		(pad "1" smd circle
			(at -0.40005 0 270)
			(size 0 0)
			(layers "F.Cu" "F.Mask" "F.Paste")
			(net "SW_PVDDIO_P1_BOOT4_R")
		)
		(pad "2" smd circle
			(at 0.40005 0 270)
			(size 0 0)
			(layers "F.Cu" "F.Mask" "F.Paste")
			(net "SW_PVDDIO_P1_BOOTR4")
		)
	)
)
